(kicad_pcb
	(version 20260206)
	(generator "pcbnew")
	(generator_version "10.0")
	(general
		(thickness 1.6)
		(legacy_teardrops no)
	)
	(paper "A4")
	(title_block
		(title "03242023_DA0F0TMBIJ0_F0T_Motherboard_J_brd_V01_OCP.brd")
		(comment 1 "Grand Teton / footprints 3594-3598 of 6105")
	)
	(layers
		(0 "F.Cu" signal "TOP")
		(4 "In1.Cu" signal "GND")
		(6 "In2.Cu" signal "IN1")
		(8 "In3.Cu" signal "GND1")
		(10 "In4.Cu" signal "IN2")
		(12 "In5.Cu" signal "GND2")
		(14 "In6.Cu" signal "IN3")
		(16 "In7.Cu" signal "GND3")
		(18 "In8.Cu" signal "VCC")
		(20 "In9.Cu" signal "VCC1")
		(22 "In10.Cu" signal "GND4")
		(24 "In11.Cu" signal "IN4")
		(26 "In12.Cu" signal "GND5")
		(28 "In13.Cu" signal "IN5")
		(30 "In14.Cu" signal "GND6")
		(32 "In15.Cu" signal "IN6")
		(34 "In16.Cu" signal "GND7")
		(2 "B.Cu" signal "BOTTOM")
		(9 "F.Adhes" user "F.Adhesive")
		(11 "B.Adhes" user "B.Adhesive")
		(13 "F.Paste" user "Package Geometry/Pastemask Top")
		(15 "B.Paste" user "Package Geometry/Pastemask Bottom")
		(5 "F.SilkS" user "Ref Des/Silkscreen Top")
		(7 "B.SilkS" user "Ref Des/Silkscreen Bottom")
		(1 "F.Mask" user "Board Geometry/Soldermask Top")
		(3 "B.Mask" user "Board Geometry/Soldermask Bottom")
		(17 "Dwgs.User" user "User.Drawings")
		(19 "Cmts.User" user "User.Comments")
		(21 "Eco1.User" user "User.Eco1")
		(23 "Eco2.User" user "User.Eco2")
		(25 "Edge.Cuts" user "Board Geometry/Outline")
		(27 "Margin" user)
		(31 "F.CrtYd" user "Package Geometry/Place Bound Top")
		(29 "B.CrtYd" user "Package Geometry/Place Bound Bottom")
		(35 "F.Fab" user "Ref Des/Assembly Top")
		(33 "B.Fab" user "Ref Des/Assembly Bottom")
	)
	(footprint ""
		(layer "F.Cu")
		(at 105.3084 -251.375672 90)
		(property "Reference" "C251"
			(at 0 0 90)
			(layer "F.SilkS")
			(hide yes)
			(effects
				(font
					(size 1.27 1.27)
				)
			)
		)
		(property "Value" ""
			(at 0 0 90)
			(layer "F.Fab")
			(effects
				(font
					(size 1.27 1.27)
				)
			)
		)
		(duplicate_pad_numbers_are_jumpers no)
		(fp_line
			(start 0.7874 -0.4064)
			(end 0.7874 0.4064)
			(stroke
				(width 0.1524)
				(type default)
			)
			(layer "F.SilkS")
		)
		(fp_line
			(start -0.7874 -0.4064)
			(end 0.7874 -0.4064)
			(stroke
				(width 0.1524)
				(type default)
			)
			(layer "F.SilkS")
		)
		(fp_line
			(start 0.7874 0.4064)
			(end -0.7874 0.4064)
			(stroke
				(width 0.1524)
				(type default)
			)
			(layer "F.SilkS")
		)
		(fp_line
			(start -0.7874 0.4064)
			(end -0.7874 -0.4064)
			(stroke
				(width 0.1524)
				(type default)
			)
			(layer "F.SilkS")
		)
		(fp_line
			(start -0.12065 -0.305054)
			(end -0.12065 -0.2794)
			(stroke
				(width 0.1)
				(type default)
			)
			(layer "F.Fab")
		)
		(fp_line
			(start -0.67945 -0.305054)
			(end -0.12065 -0.305054)
			(stroke
				(width 0.1)
				(type default)
			)
			(layer "F.Fab")
		)
		(fp_line
			(start 0.67945 -0.3048)
			(end 0.67945 0.3048)
			(stroke
				(width 0.1)
				(type default)
			)
			(layer "F.Fab")
		)
		(fp_line
			(start 0.12065 -0.3048)
			(end 0.67945 -0.3048)
			(stroke
				(width 0.1)
				(type default)
			)
			(layer "F.Fab")
		)
		(fp_line
			(start 0.12065 -0.2794)
			(end 0.12065 -0.3048)
			(stroke
				(width 0.1)
				(type default)
			)
			(layer "F.Fab")
		)
		(fp_line
			(start -0.12065 -0.2794)
			(end 0.12065 -0.2794)
			(stroke
				(width 0.1)
				(type default)
			)
			(layer "F.Fab")
		)
		(fp_line
			(start 0.120396 0.2794)
			(end -0.12065 0.2794)
			(stroke
				(width 0.1)
				(type default)
			)
			(layer "F.Fab")
		)
		(fp_line
			(start -0.12065 0.2794)
			(end -0.12065 0.3048)
			(stroke
				(width 0.1)
				(type default)
			)
			(layer "F.Fab")
		)
		(fp_line
			(start 0.67945 0.3048)
			(end 0.120396 0.3048)
			(stroke
				(width 0.1)
				(type default)
			)
			(layer "F.Fab")
		)
		(fp_line
			(start 0.120396 0.3048)
			(end 0.120396 0.2794)
			(stroke
				(width 0.1)
				(type default)
			)
			(layer "F.Fab")
		)
		(fp_line
			(start -0.12065 0.3048)
			(end -0.67945 0.3048)
			(stroke
				(width 0.1)
				(type default)
			)
			(layer "F.Fab")
		)
		(fp_line
			(start -0.67945 0.3048)
			(end -0.67945 -0.305054)
			(stroke
				(width 0.1)
				(type default)
			)
			(layer "F.Fab")
		)
		(pad "1" smd circle
			(at -0.40005 0 90)
			(size 0 0)
			(layers "F.Cu" "F.Mask" "F.Paste")
			(net "PVCCIN_CPU1")
		)
		(pad "2" smd circle
			(at 0.40005 0 90)
			(size 0 0)
			(layers "F.Cu" "F.Mask" "F.Paste")
			(net "GND")
		)
	)
	(footprint ""
		(layer "F.Cu")
		(at 84.270342 -343.015062 -90)
		(property "Reference" "PC486_P1_7"
			(at 0 0 270)
			(layer "F.SilkS")
			(hide yes)
			(effects
				(font
					(size 1.27 1.27)
				)
			)
		)
		(property "Value" ""
			(at 0 0 270)
			(layer "F.Fab")
			(effects
				(font
					(size 1.27 1.27)
				)
			)
		)
		(duplicate_pad_numbers_are_jumpers no)
		(fp_line
			(start -0.7874 0.4064)
			(end -0.7874 -0.4064)
			(stroke
				(width 0.1524)
				(type default)
			)
			(layer "F.SilkS")
		)
		(fp_line
			(start 0.7874 0.4064)
			(end -0.7874 0.4064)
			(stroke
				(width 0.1524)
				(type default)
			)
			(layer "F.SilkS")
		)
		(fp_line
			(start -0.7874 -0.4064)
			(end 0.7874 -0.4064)
			(stroke
				(width 0.1524)
				(type default)
			)
			(layer "F.SilkS")
		)
		(fp_line
			(start 0.7874 -0.4064)
			(end 0.7874 0.4064)
			(stroke
				(width 0.1524)
				(type default)
			)
			(layer "F.SilkS")
		)
		(fp_line
			(start -0.67945 0.3048)
			(end -0.67945 -0.305054)
			(stroke
				(width 0.1)
				(type default)
			)
			(layer "F.Fab")
		)
		(fp_line
			(start -0.12065 0.3048)
			(end -0.67945 0.3048)
			(stroke
				(width 0.1)
				(type default)
			)
			(layer "F.Fab")
		)
		(fp_line
			(start 0.120396 0.3048)
			(end 0.120396 0.2794)
			(stroke
				(width 0.1)
				(type default)
			)
			(layer "F.Fab")
		)
		(fp_line
			(start 0.67945 0.3048)
			(end 0.120396 0.3048)
			(stroke
				(width 0.1)
				(type default)
			)
			(layer "F.Fab")
		)
		(fp_line
			(start -0.12065 0.2794)
			(end -0.12065 0.3048)
			(stroke
				(width 0.1)
				(type default)
			)
			(layer "F.Fab")
		)
		(fp_line
			(start 0.120396 0.2794)
			(end -0.12065 0.2794)
			(stroke
				(width 0.1)
				(type default)
			)
			(layer "F.Fab")
		)
		(fp_line
			(start -0.12065 -0.2794)
			(end 0.12065 -0.2794)
			(stroke
				(width 0.1)
				(type default)
			)
			(layer "F.Fab")
		)
		(fp_line
			(start 0.12065 -0.2794)
			(end 0.12065 -0.3048)
			(stroke
				(width 0.1)
				(type default)
			)
			(layer "F.Fab")
		)
		(fp_line
			(start 0.12065 -0.3048)
			(end 0.67945 -0.3048)
			(stroke
				(width 0.1)
				(type default)
			)
			(layer "F.Fab")
		)
		(fp_line
			(start 0.67945 -0.3048)
			(end 0.67945 0.3048)
			(stroke
				(width 0.1)
				(type default)
			)
			(layer "F.Fab")
		)
		(fp_line
			(start -0.67945 -0.305054)
			(end -0.12065 -0.305054)
			(stroke
				(width 0.1)
				(type default)
			)
			(layer "F.Fab")
		)
		(fp_line
			(start -0.12065 -0.305054)
			(end -0.12065 -0.2794)
			(stroke
				(width 0.1)
				(type default)
			)
			(layer "F.Fab")
		)
		(pad "1" smd circle
			(at -0.40005 0 270)
			(size 0 0)
			(layers "F.Cu" "F.Mask" "F.Paste")
			(net "SW_P12V_PVCCIN_CPU1_FLT")
		)
		(pad "2" smd circle
			(at 0.40005 0 270)
			(size 0 0)
			(layers "F.Cu" "F.Mask" "F.Paste")
			(net "GND")
		)
	)
	(footprint ""
		(layer "F.Cu")
		(at 23.10511 -179.928266)
		(property "Reference" "PU82"
			(at -4.4704 7.05358 0)
			(unlocked yes)
			(layer "F.SilkS")
			(effects
				(font
					(size 0.7874 0.5842)
					(thickness 0.1524)
				)
				(justify left)
			)
		)
		(property "Value" ""
			(at 0 0 0)
			(layer "F.Fab")
			(effects
				(font
					(size 1.27 1.27)
				)
			)
		)
		(duplicate_pad_numbers_are_jumpers no)
		(fp_line
			(start -1.050036 -1.549908)
			(end -0.503936 -1.549908)
			(stroke
				(width 0.1524)
				(type default)
			)
			(layer "F.SilkS")
		)
		(fp_line
			(start -1.050036 -1.253998)
			(end -1.050036 -1.549908)
			(stroke
				(width 0.1524)
				(type default)
			)
			(layer "F.SilkS")
		)
		(fp_line
			(start -1.050036 1.549908)
			(end -1.050036 1.253998)
			(stroke
				(width 0.1524)
				(type default)
			)
			(layer "F.SilkS")
		)
		(fp_line
			(start -0.503936 1.549908)
			(end -1.050036 1.549908)
			(stroke
				(width 0.1524)
				(type default)
			)
			(layer "F.SilkS")
		)
		(fp_line
			(start 0.503936 -1.549908)
			(end 1.050036 -1.549908)
			(stroke
				(width 0.1524)
				(type default)
			)
			(layer "F.SilkS")
		)
		(fp_line
			(start 1.050036 -1.549908)
			(end 1.050036 -1.253998)
			(stroke
				(width 0.1524)
				(type default)
			)
			(layer "F.SilkS")
		)
		(fp_line
			(start 1.050036 1.253998)
			(end 1.050036 1.549908)
			(stroke
				(width 0.1524)
				(type default)
			)
			(layer "F.SilkS")
		)
		(fp_line
			(start 1.050036 1.549908)
			(end 0.503936 1.549908)
			(stroke
				(width 0.1524)
				(type default)
			)
			(layer "F.SilkS")
		)
		(fp_poly
			(pts
				(xy -1.474724 -2.460498) (xy -1.385824 -1.613154) (xy -2.11709 -2.050288)
			)
			(stroke
				(width 0)
				(type default)
			)
			(fill yes)
			(layer "F.SilkS")
		)
		(fp_line
			(start -1.050036 -1.549908)
			(end 1.050036 -1.549908)
			(stroke
				(width 0.1)
				(type default)
			)
			(layer "F.Fab")
		)
		(fp_line
			(start -1.050036 1.549908)
			(end -1.050036 -1.549908)
			(stroke
				(width 0.1)
				(type default)
			)
			(layer "F.Fab")
		)
		(fp_line
			(start 1.050036 -1.549908)
			(end 1.050036 1.549908)
			(stroke
				(width 0.1)
				(type default)
			)
			(layer "F.Fab")
		)
		(fp_line
			(start 1.050036 1.549908)
			(end -1.050036 1.549908)
			(stroke
				(width 0.1)
				(type default)
			)
			(layer "F.Fab")
		)
		(fp_poly
			(pts
				(xy -2.2352 -0.618998) (xy -2.2352 -1.380998) (xy -1.4732 -0.999998)
			)
			(stroke
				(width 0)
				(type default)
			)
			(fill yes)
			(layer "F.Fab")
		)
		(pad "1" smd circle
			(at -0.94996 -0.999998 270)
			(size 0 0)
			(layers "F.Cu" "F.Mask" "F.Paste")
			(net "GND")
		)
		(pad "2" smd rect
			(at -0.849884 -0.499872 90)
			(size 0.254 0.9144)
			(layers "F.Cu" "F.Mask" "F.Paste")
			(net "SW_PVNN_MAIN_CPU1_SW")
		)
		(pad "3" smd rect
			(at -0.649986 0 90)
			(size 0.254 1.3208)
			(layers "F.Cu" "F.Mask" "F.Paste")
			(net "SW_P12V_PVCCINFAON_CPU1_FLT")
		)
		(pad "4" smd rect
			(at -0.849884 0.499872 90)
			(size 0.254 0.9144)
			(layers "F.Cu" "F.Mask" "F.Paste")
			(net "PVNN_MAIN_CPU1_CS")
		)
		(pad "5" smd circle
			(at -0.94996 0.999998 270)
			(size 0 0)
			(layers "F.Cu" "F.Mask" "F.Paste")
			(net "FM_PVNN_MAIN_CPU1_EN")
		)
		(pad "6" smd circle
			(at -0.249936 1.450086)
			(size 0 0)
			(layers "F.Cu" "F.Mask" "F.Paste")
			(net "PVNN_MAIN_CPU1_FB")
		)
		(pad "7" smd circle
			(at 0.249936 1.450086)
			(size 0 0)
			(layers "F.Cu" "F.Mask" "F.Paste")
			(net "GND")
		)
		(pad "8" smd circle
			(at 0.94996 0.999998 90)
			(size 0 0)
			(layers "F.Cu" "F.Mask" "F.Paste")
			(net "PVNN_MAIN_CPU1_REF")
		)
		(pad "9" smd rect
			(at 0.849884 0.499872 90)
			(size 0.254 0.9144)
			(layers "F.Cu" "F.Mask" "F.Paste")
			(net "PWRGD_PVNN_MAIN_CPU1_R")
		)
		(pad "10" smd rect
			(at 0.849884 0 90)
			(size 0.254 0.9144)
			(layers "F.Cu" "F.Mask" "F.Paste")
			(net "SW_PVNN_MAIN_CPU1_BST")
		)
		(pad "11" smd rect
			(at 0.849884 -0.499872 90)
			(size 0.254 0.9144)
			(layers "F.Cu" "F.Mask" "F.Paste")
			(net "SW_PVNN_MAIN_CPU1_SW")
		)
		(pad "12" smd circle
			(at 0.94996 -0.999998 90)
			(size 0 0)
			(layers "F.Cu" "F.Mask" "F.Paste")
			(net "PVNN_MAIN_CPU1_MODE")
		)
		(pad "13" smd circle
			(at 0.249936 -1.450086 180)
			(size 0 0)
			(layers "F.Cu" "F.Mask" "F.Paste")
			(net "PVNN_MAIN_CPU1_VCC")
		)
		(pad "14" smd circle
			(at -0.249936 -1.450086 180)
			(size 0 0)
			(layers "F.Cu" "F.Mask" "F.Paste")
			(net "GND")
		)
	)
	(footprint ""
		(layer "F.Cu")
		(at 132.382514 -402.371052 -90)
		(property "Reference" "C751"
			(at 0 0 270)
			(layer "F.SilkS")
			(hide yes)
			(effects
				(font
					(size 1.27 1.27)
				)
			)
		)
		(property "Value" ""
			(at 0 0 270)
			(layer "F.Fab")
			(effects
				(font
					(size 1.27 1.27)
				)
			)
		)
		(duplicate_pad_numbers_are_jumpers no)
		(fp_line
			(start -0.299974 0.150114)
			(end -0.299974 -0.150114)
			(stroke
				(width 0.1)
				(type default)
			)
			(layer "F.Fab")
		)
		(fp_line
			(start 0.299974 0.150114)
			(end -0.299974 0.150114)
			(stroke
				(width 0.1)
				(type default)
			)
			(layer "F.Fab")
		)
		(fp_line
			(start -0.299974 -0.150114)
			(end 0.299974 -0.150114)
			(stroke
				(width 0.1)
				(type default)
			)
			(layer "F.Fab")
		)
		(fp_line
			(start 0.299974 -0.150114)
			(end 0.299974 0.150114)
			(stroke
				(width 0.1)
				(type default)
			)
			(layer "F.Fab")
		)
		(pad "1" smd rect
			(at -0.2667 0 270)
			(size 0.3048 0.381)
			(layers "F.Cu" "F.Mask" "F.Paste")
			(net "P5E_CPU1_PE2_TX_C_DP<11>")
		)
		(pad "2" smd rect
			(at 0.2667 0 270)
			(size 0.3048 0.381)
			(layers "F.Cu" "F.Mask" "F.Paste")
			(net "P5E_CPU1_PE2_TX_DP<11>")
		)
	)
	(footprint ""
		(layer "F.Cu")
		(at 160.83788 -107.025948)
		(property "Reference" "R3043"
			(at 0 0 0)
			(layer "F.SilkS")
			(hide yes)
			(effects
				(font
					(size 1.27 1.27)
				)
			)
		)
		(property "Value" ""
			(at 0 0 0)
			(layer "F.Fab")
			(effects
				(font
					(size 1.27 1.27)
				)
			)
		)
		(duplicate_pad_numbers_are_jumpers no)
		(fp_line
			(start -0.7874 -0.4064)
			(end 0.7874 -0.4064)
			(stroke
				(width 0.1524)
				(type default)
			)
			(layer "F.SilkS")
		)
		(fp_line
			(start -0.7874 0.4064)
			(end -0.7874 -0.4064)
			(stroke
				(width 0.1524)
				(type default)
			)
			(layer "F.SilkS")
		)
		(fp_line
			(start 0.7874 -0.4064)
			(end 0.7874 0.4064)
			(stroke
				(width 0.1524)
				(type default)
			)
			(layer "F.SilkS")
		)
		(fp_line
			(start 0.7874 0.4064)
			(end -0.7874 0.4064)
			(stroke
				(width 0.1524)
				(type default)
			)
			(layer "F.SilkS")
		)
		(fp_line
			(start -0.67945 -0.305054)
			(end -0.12065 -0.305054)
			(stroke
				(width 0.1)
				(type default)
			)
			(layer "F.Fab")
		)
		(fp_line
			(start -0.67945 0.3048)
			(end -0.67945 -0.305054)
			(stroke
				(width 0.1)
				(type default)
			)
			(layer "F.Fab")
		)
		(fp_line
			(start -0.12065 -0.305054)
			(end -0.12065 -0.2794)
			(stroke
				(width 0.1)
				(type default)
			)
			(layer "F.Fab")
		)
		(fp_line
			(start -0.12065 -0.2794)
			(end 0.12065 -0.2794)
			(stroke
				(width 0.1)
				(type default)
			)
			(layer "F.Fab")
		)
		(fp_line
			(start -0.12065 0.2794)
			(end -0.12065 0.3048)
			(stroke
				(width 0.1)
				(type default)
			)
			(layer "F.Fab")
		)
		(fp_line
			(start -0.12065 0.3048)
			(end -0.67945 0.3048)
			(stroke
				(width 0.1)
				(type default)
			)
			(layer "F.Fab")
		)
		(fp_line
			(start 0.120396 0.2794)
			(end -0.12065 0.2794)
			(stroke
				(width 0.1)
				(type default)
			)
			(layer "F.Fab")
		)
		(fp_line
			(start 0.120396 0.3048)
			(end 0.120396 0.2794)
			(stroke
				(width 0.1)
				(type default)
			)
			(layer "F.Fab")
		)
		(fp_line
			(start 0.12065 -0.3048)
			(end 0.67945 -0.3048)
			(stroke
				(width 0.1)
				(type default)
			)
			(layer "F.Fab")
		)
		(fp_line
			(start 0.12065 -0.2794)
			(end 0.12065 -0.3048)
			(stroke
				(width 0.1)
				(type default)
			)
			(layer "F.Fab")
		)
		(fp_line
			(start 0.67945 -0.3048)
			(end 0.67945 0.3048)
			(stroke
				(width 0.1)
				(type default)
			)
			(layer "F.Fab")
		)
		(fp_line
			(start 0.67945 0.3048)
			(end 0.120396 0.3048)
			(stroke
				(width 0.1)
				(type default)
			)
			(layer "F.Fab")
		)
		(pad "1" smd circle
			(at -0.40005 0)
			(size 0 0)
			(layers "F.Cu" "F.Mask" "F.Paste")
			(net "IRQ_HSC_FAULT_N")
		)
		(pad "2" smd circle
			(at 0.40005 0)
			(size 0 0)
			(layers "F.Cu" "F.Mask" "F.Paste")
			(net "IRQ_HSC_FAULT_R1_N")
		)
	)
)
